(kicad_pcb
	(version 20260206)
	(generator "pcbnew")
	(generator_version "10.0")
	(general
		(thickness 1.6)
		(legacy_teardrops no)
	)
	(paper "A4")
	(title_block
		(title "01162023_DA0F0TEBIF0_F0T_Expander_BD_F_brd_V02_OCP.brd")
		(comment 1 "Grand Teton / footprints 4932-4937 of 9728")
	)
	(layers
		(0 "F.Cu" signal "TOP")
		(4 "In1.Cu" signal "GND")
		(6 "In2.Cu" signal "VCC")
		(8 "In3.Cu" signal "VCC1")
		(10 "In4.Cu" signal "GND1")
		(12 "In5.Cu" signal "IN1")
		(14 "In6.Cu" signal "GND2")
		(16 "In7.Cu" signal "IN2")
		(18 "In8.Cu" signal "GND3")
		(20 "In9.Cu" signal "IN3")
		(22 "In10.Cu" signal "GND4")
		(24 "In11.Cu" signal "IN4")
		(26 "In12.Cu" signal "GND5")
		(28 "In13.Cu" signal "IN5")
		(30 "In14.Cu" signal "GND6")
		(32 "In15.Cu" signal "IN6")
		(34 "In16.Cu" signal "GND7")
		(2 "B.Cu" signal "BOTTOM")
		(9 "F.Adhes" user "F.Adhesive")
		(11 "B.Adhes" user "B.Adhesive")
		(13 "F.Paste" user "Package Geometry/Pastemask Top")
		(15 "B.Paste" user "Package Geometry/Pastemask Bottom")
		(5 "F.SilkS" user "Ref Des/Silkscreen Top")
		(7 "B.SilkS" user "Ref Des/Silkscreen Bottom")
		(1 "F.Mask" user "Board Geometry/Soldermask Top")
		(3 "B.Mask" user "Board Geometry/Soldermask Bottom")
		(17 "Dwgs.User" user "User.Drawings")
		(19 "Cmts.User" user "User.Comments")
		(21 "Eco1.User" user "User.Eco1")
		(23 "Eco2.User" user "User.Eco2")
		(25 "Edge.Cuts" user "Board Geometry/Outline")
		(27 "Margin" user)
		(31 "F.CrtYd" user "Package Geometry/Place Bound Top")
		(29 "B.CrtYd" user "Package Geometry/Place Bound Bottom")
		(35 "F.Fab" user "Ref Des/Assembly Top")
		(33 "B.Fab" user "Ref Des/Assembly Bottom")
	)
	(footprint ""
		(layer "F.Cu")
		(at 362.696506 -386.172456)
		(property "Reference" "R6709"
			(at 0 0 0)
			(layer "F.SilkS")
			(hide yes)
			(effects
				(font
					(size 1.27 1.27)
				)
			)
		)
		(property "Value" ""
			(at 0 0 0)
			(layer "F.Fab")
			(effects
				(font
					(size 1.27 1.27)
				)
			)
		)
		(duplicate_pad_numbers_are_jumpers no)
		(fp_line
			(start -0.7874 -0.4064)
			(end 0.7874 -0.4064)
			(stroke
				(width 0.1524)
				(type default)
			)
			(layer "F.SilkS")
		)
		(fp_line
			(start -0.7874 0.4064)
			(end -0.7874 -0.4064)
			(stroke
				(width 0.1524)
				(type default)
			)
			(layer "F.SilkS")
		)
		(fp_line
			(start 0.7874 -0.4064)
			(end 0.7874 0.4064)
			(stroke
				(width 0.1524)
				(type default)
			)
			(layer "F.SilkS")
		)
		(fp_line
			(start 0.7874 0.4064)
			(end -0.7874 0.4064)
			(stroke
				(width 0.1524)
				(type default)
			)
			(layer "F.SilkS")
		)
		(fp_line
			(start -0.67945 -0.305054)
			(end -0.12065 -0.305054)
			(stroke
				(width 0.1)
				(type default)
			)
			(layer "F.Fab")
		)
		(fp_line
			(start -0.67945 0.3048)
			(end -0.67945 -0.305054)
			(stroke
				(width 0.1)
				(type default)
			)
			(layer "F.Fab")
		)
		(fp_line
			(start -0.12065 -0.305054)
			(end -0.12065 -0.2794)
			(stroke
				(width 0.1)
				(type default)
			)
			(layer "F.Fab")
		)
		(fp_line
			(start -0.12065 -0.2794)
			(end 0.12065 -0.2794)
			(stroke
				(width 0.1)
				(type default)
			)
			(layer "F.Fab")
		)
		(fp_line
			(start -0.12065 0.2794)
			(end -0.12065 0.3048)
			(stroke
				(width 0.1)
				(type default)
			)
			(layer "F.Fab")
		)
		(fp_line
			(start -0.12065 0.3048)
			(end -0.67945 0.3048)
			(stroke
				(width 0.1)
				(type default)
			)
			(layer "F.Fab")
		)
		(fp_line
			(start 0.120396 0.2794)
			(end -0.12065 0.2794)
			(stroke
				(width 0.1)
				(type default)
			)
			(layer "F.Fab")
		)
		(fp_line
			(start 0.120396 0.3048)
			(end 0.120396 0.2794)
			(stroke
				(width 0.1)
				(type default)
			)
			(layer "F.Fab")
		)
		(fp_line
			(start 0.12065 -0.3048)
			(end 0.67945 -0.3048)
			(stroke
				(width 0.1)
				(type default)
			)
			(layer "F.Fab")
		)
		(fp_line
			(start 0.12065 -0.2794)
			(end 0.12065 -0.3048)
			(stroke
				(width 0.1)
				(type default)
			)
			(layer "F.Fab")
		)
		(fp_line
			(start 0.67945 -0.3048)
			(end 0.67945 0.3048)
			(stroke
				(width 0.1)
				(type default)
			)
			(layer "F.Fab")
		)
		(fp_line
			(start 0.67945 0.3048)
			(end 0.120396 0.3048)
			(stroke
				(width 0.1)
				(type default)
			)
			(layer "F.Fab")
		)
		(pad "1" smd circle
			(at -0.40005 0)
			(size 0 0)
			(layers "F.Cu" "F.Mask" "F.Paste")
			(net "P3V3_AUX")
		)
		(pad "2" smd circle
			(at 0.40005 0)
			(size 0 0)
			(layers "F.Cu" "F.Mask" "F.Paste")
			(net "MB_3V3IO_RSVD4")
		)
	)
	(footprint ""
		(layer "F.Cu")
		(at 359.156 -192.278 180)
		(property "Reference" "R4640"
			(at 0 0 180)
			(layer "F.SilkS")
			(hide yes)
			(effects
				(font
					(size 1.27 1.27)
				)
			)
		)
		(property "Value" ""
			(at 0 0 180)
			(layer "F.Fab")
			(effects
				(font
					(size 1.27 1.27)
				)
			)
		)
		(duplicate_pad_numbers_are_jumpers no)
		(fp_line
			(start 0.7874 0.4064)
			(end -0.7874 0.4064)
			(stroke
				(width 0.1524)
				(type default)
			)
			(layer "F.SilkS")
		)
		(fp_line
			(start 0.7874 -0.4064)
			(end 0.7874 0.4064)
			(stroke
				(width 0.1524)
				(type default)
			)
			(layer "F.SilkS")
		)
		(fp_line
			(start -0.7874 0.4064)
			(end -0.7874 -0.4064)
			(stroke
				(width 0.1524)
				(type default)
			)
			(layer "F.SilkS")
		)
		(fp_line
			(start -0.7874 -0.4064)
			(end 0.7874 -0.4064)
			(stroke
				(width 0.1524)
				(type default)
			)
			(layer "F.SilkS")
		)
		(fp_line
			(start 0.67945 0.3048)
			(end 0.120396 0.3048)
			(stroke
				(width 0.1)
				(type default)
			)
			(layer "F.Fab")
		)
		(fp_line
			(start 0.67945 -0.3048)
			(end 0.67945 0.3048)
			(stroke
				(width 0.1)
				(type default)
			)
			(layer "F.Fab")
		)
		(fp_line
			(start 0.12065 -0.2794)
			(end 0.12065 -0.3048)
			(stroke
				(width 0.1)
				(type default)
			)
			(layer "F.Fab")
		)
		(fp_line
			(start 0.12065 -0.3048)
			(end 0.67945 -0.3048)
			(stroke
				(width 0.1)
				(type default)
			)
			(layer "F.Fab")
		)
		(fp_line
			(start 0.120396 0.3048)
			(end 0.120396 0.2794)
			(stroke
				(width 0.1)
				(type default)
			)
			(layer "F.Fab")
		)
		(fp_line
			(start 0.120396 0.2794)
			(end -0.12065 0.2794)
			(stroke
				(width 0.1)
				(type default)
			)
			(layer "F.Fab")
		)
		(fp_line
			(start -0.12065 0.3048)
			(end -0.67945 0.3048)
			(stroke
				(width 0.1)
				(type default)
			)
			(layer "F.Fab")
		)
		(fp_line
			(start -0.12065 0.2794)
			(end -0.12065 0.3048)
			(stroke
				(width 0.1)
				(type default)
			)
			(layer "F.Fab")
		)
		(fp_line
			(start -0.12065 -0.2794)
			(end 0.12065 -0.2794)
			(stroke
				(width 0.1)
				(type default)
			)
			(layer "F.Fab")
		)
		(fp_line
			(start -0.12065 -0.305054)
			(end -0.12065 -0.2794)
			(stroke
				(width 0.1)
				(type default)
			)
			(layer "F.Fab")
		)
		(fp_line
			(start -0.67945 0.3048)
			(end -0.67945 -0.305054)
			(stroke
				(width 0.1)
				(type default)
			)
			(layer "F.Fab")
		)
		(fp_line
			(start -0.67945 -0.305054)
			(end -0.12065 -0.305054)
			(stroke
				(width 0.1)
				(type default)
			)
			(layer "F.Fab")
		)
		(pad "1" smd circle
			(at -0.40005 0 180)
			(size 0 0)
			(layers "F.Cu" "F.Mask" "F.Paste")
			(net "PCA9555_1_PEX0_A1")
		)
		(pad "2" smd circle
			(at 0.40005 0 180)
			(size 0 0)
			(layers "F.Cu" "F.Mask" "F.Paste")
			(net "P3V3_AUX")
		)
	)
	(footprint ""
		(layer "F.Cu")
		(at 258.46786 -51.019456)
		(property "Reference" "PC410"
			(at 0 0 0)
			(layer "F.SilkS")
			(hide yes)
			(effects
				(font
					(size 1.27 1.27)
				)
			)
		)
		(property "Value" ""
			(at 0 0 0)
			(layer "F.Fab")
			(effects
				(font
					(size 1.27 1.27)
				)
			)
		)
		(duplicate_pad_numbers_are_jumpers no)
		(fp_line
			(start -0.7874 -0.4064)
			(end 0.7874 -0.4064)
			(stroke
				(width 0.1524)
				(type default)
			)
			(layer "F.SilkS")
		)
		(fp_line
			(start -0.7874 0.4064)
			(end -0.7874 -0.4064)
			(stroke
				(width 0.1524)
				(type default)
			)
			(layer "F.SilkS")
		)
		(fp_line
			(start 0.7874 -0.4064)
			(end 0.7874 0.4064)
			(stroke
				(width 0.1524)
				(type default)
			)
			(layer "F.SilkS")
		)
		(fp_line
			(start 0.7874 0.4064)
			(end -0.7874 0.4064)
			(stroke
				(width 0.1524)
				(type default)
			)
			(layer "F.SilkS")
		)
		(fp_line
			(start -0.67945 -0.305054)
			(end -0.12065 -0.305054)
			(stroke
				(width 0.1)
				(type default)
			)
			(layer "F.Fab")
		)
		(fp_line
			(start -0.67945 0.3048)
			(end -0.67945 -0.305054)
			(stroke
				(width 0.1)
				(type default)
			)
			(layer "F.Fab")
		)
		(fp_line
			(start -0.12065 -0.305054)
			(end -0.12065 -0.2794)
			(stroke
				(width 0.1)
				(type default)
			)
			(layer "F.Fab")
		)
		(fp_line
			(start -0.12065 -0.2794)
			(end 0.12065 -0.2794)
			(stroke
				(width 0.1)
				(type default)
			)
			(layer "F.Fab")
		)
		(fp_line
			(start -0.12065 0.2794)
			(end -0.12065 0.3048)
			(stroke
				(width 0.1)
				(type default)
			)
			(layer "F.Fab")
		)
		(fp_line
			(start -0.12065 0.3048)
			(end -0.67945 0.3048)
			(stroke
				(width 0.1)
				(type default)
			)
			(layer "F.Fab")
		)
		(fp_line
			(start 0.120396 0.2794)
			(end -0.12065 0.2794)
			(stroke
				(width 0.1)
				(type default)
			)
			(layer "F.Fab")
		)
		(fp_line
			(start 0.120396 0.3048)
			(end 0.120396 0.2794)
			(stroke
				(width 0.1)
				(type default)
			)
			(layer "F.Fab")
		)
		(fp_line
			(start 0.12065 -0.3048)
			(end 0.67945 -0.3048)
			(stroke
				(width 0.1)
				(type default)
			)
			(layer "F.Fab")
		)
		(fp_line
			(start 0.12065 -0.2794)
			(end 0.12065 -0.3048)
			(stroke
				(width 0.1)
				(type default)
			)
			(layer "F.Fab")
		)
		(fp_line
			(start 0.67945 -0.3048)
			(end 0.67945 0.3048)
			(stroke
				(width 0.1)
				(type default)
			)
			(layer "F.Fab")
		)
		(fp_line
			(start 0.67945 0.3048)
			(end 0.120396 0.3048)
			(stroke
				(width 0.1)
				(type default)
			)
			(layer "F.Fab")
		)
		(pad "1" smd circle
			(at -0.40005 0)
			(size 0 0)
			(layers "F.Cu" "F.Mask" "F.Paste")
			(net "P12V_SSD8_SS")
		)
		(pad "2" smd circle
			(at 0.40005 0)
			(size 0 0)
			(layers "F.Cu" "F.Mask" "F.Paste")
			(net "GND")
		)
	)
	(footprint ""
		(layer "F.Cu")
		(at 26.243788 -48.93691 180)
		(property "Reference" "R512"
			(at 0 0 180)
			(layer "F.SilkS")
			(hide yes)
			(effects
				(font
					(size 1.27 1.27)
				)
			)
		)
		(property "Value" ""
			(at 0 0 180)
			(layer "F.Fab")
			(effects
				(font
					(size 1.27 1.27)
				)
			)
		)
		(duplicate_pad_numbers_are_jumpers no)
		(fp_line
			(start 0.7874 0.4064)
			(end -0.7874 0.4064)
			(stroke
				(width 0.1524)
				(type default)
			)
			(layer "F.SilkS")
		)
		(fp_line
			(start 0.7874 -0.4064)
			(end 0.7874 0.4064)
			(stroke
				(width 0.1524)
				(type default)
			)
			(layer "F.SilkS")
		)
		(fp_line
			(start -0.7874 0.4064)
			(end -0.7874 -0.4064)
			(stroke
				(width 0.1524)
				(type default)
			)
			(layer "F.SilkS")
		)
		(fp_line
			(start -0.7874 -0.4064)
			(end 0.7874 -0.4064)
			(stroke
				(width 0.1524)
				(type default)
			)
			(layer "F.SilkS")
		)
		(fp_line
			(start 0.67945 0.3048)
			(end 0.120396 0.3048)
			(stroke
				(width 0.1)
				(type default)
			)
			(layer "F.Fab")
		)
		(fp_line
			(start 0.67945 -0.3048)
			(end 0.67945 0.3048)
			(stroke
				(width 0.1)
				(type default)
			)
			(layer "F.Fab")
		)
		(fp_line
			(start 0.12065 -0.2794)
			(end 0.12065 -0.3048)
			(stroke
				(width 0.1)
				(type default)
			)
			(layer "F.Fab")
		)
		(fp_line
			(start 0.12065 -0.3048)
			(end 0.67945 -0.3048)
			(stroke
				(width 0.1)
				(type default)
			)
			(layer "F.Fab")
		)
		(fp_line
			(start 0.120396 0.3048)
			(end 0.120396 0.2794)
			(stroke
				(width 0.1)
				(type default)
			)
			(layer "F.Fab")
		)
		(fp_line
			(start 0.120396 0.2794)
			(end -0.12065 0.2794)
			(stroke
				(width 0.1)
				(type default)
			)
			(layer "F.Fab")
		)
		(fp_line
			(start -0.12065 0.3048)
			(end -0.67945 0.3048)
			(stroke
				(width 0.1)
				(type default)
			)
			(layer "F.Fab")
		)
		(fp_line
			(start -0.12065 0.2794)
			(end -0.12065 0.3048)
			(stroke
				(width 0.1)
				(type default)
			)
			(layer "F.Fab")
		)
		(fp_line
			(start -0.12065 -0.2794)
			(end 0.12065 -0.2794)
			(stroke
				(width 0.1)
				(type default)
			)
			(layer "F.Fab")
		)
		(fp_line
			(start -0.12065 -0.305054)
			(end -0.12065 -0.2794)
			(stroke
				(width 0.1)
				(type default)
			)
			(layer "F.Fab")
		)
		(fp_line
			(start -0.67945 0.3048)
			(end -0.67945 -0.305054)
			(stroke
				(width 0.1)
				(type default)
			)
			(layer "F.Fab")
		)
		(fp_line
			(start -0.67945 -0.305054)
			(end -0.12065 -0.305054)
			(stroke
				(width 0.1)
				(type default)
			)
			(layer "F.Fab")
		)
		(pad "1" smd circle
			(at -0.40005 0 180)
			(size 0 0)
			(layers "F.Cu" "F.Mask" "F.Paste")
			(net "SMB_BIC_I2C6_MUX_SSD_0_7_ADC_R_SDA")
		)
		(pad "2" smd circle
			(at 0.40005 0 180)
			(size 0 0)
			(layers "F.Cu" "F.Mask" "F.Paste")
			(net "SMB_SSD0_ADC_SDA")
		)
	)
	(footprint ""
		(layer "F.Cu")
		(at 287.557718 -27.006296 -90)
		(property "Reference" "PR7119"
			(at 0 0 270)
			(layer "F.SilkS")
			(hide yes)
			(effects
				(font
					(size 1.27 1.27)
				)
			)
		)
		(property "Value" ""
			(at 0 0 270)
			(layer "F.Fab")
			(effects
				(font
					(size 1.27 1.27)
				)
			)
		)
		(duplicate_pad_numbers_are_jumpers no)
		(fp_line
			(start -0.7874 0.4064)
			(end -0.7874 -0.4064)
			(stroke
				(width 0.1524)
				(type default)
			)
			(layer "F.SilkS")
		)
		(fp_line
			(start 0.7874 0.4064)
			(end -0.7874 0.4064)
			(stroke
				(width 0.1524)
				(type default)
			)
			(layer "F.SilkS")
		)
		(fp_line
			(start -0.7874 -0.4064)
			(end 0.7874 -0.4064)
			(stroke
				(width 0.1524)
				(type default)
			)
			(layer "F.SilkS")
		)
		(fp_line
			(start 0.7874 -0.4064)
			(end 0.7874 0.4064)
			(stroke
				(width 0.1524)
				(type default)
			)
			(layer "F.SilkS")
		)
		(fp_line
			(start -0.67945 0.3048)
			(end -0.67945 -0.305054)
			(stroke
				(width 0.1)
				(type default)
			)
			(layer "F.Fab")
		)
		(fp_line
			(start -0.12065 0.3048)
			(end -0.67945 0.3048)
			(stroke
				(width 0.1)
				(type default)
			)
			(layer "F.Fab")
		)
		(fp_line
			(start 0.120396 0.3048)
			(end 0.120396 0.2794)
			(stroke
				(width 0.1)
				(type default)
			)
			(layer "F.Fab")
		)
		(fp_line
			(start 0.67945 0.3048)
			(end 0.120396 0.3048)
			(stroke
				(width 0.1)
				(type default)
			)
			(layer "F.Fab")
		)
		(fp_line
			(start -0.12065 0.2794)
			(end -0.12065 0.3048)
			(stroke
				(width 0.1)
				(type default)
			)
			(layer "F.Fab")
		)
		(fp_line
			(start 0.120396 0.2794)
			(end -0.12065 0.2794)
			(stroke
				(width 0.1)
				(type default)
			)
			(layer "F.Fab")
		)
		(fp_line
			(start -0.12065 -0.2794)
			(end 0.12065 -0.2794)
			(stroke
				(width 0.1)
				(type default)
			)
			(layer "F.Fab")
		)
		(fp_line
			(start 0.12065 -0.2794)
			(end 0.12065 -0.3048)
			(stroke
				(width 0.1)
				(type default)
			)
			(layer "F.Fab")
		)
		(fp_line
			(start 0.12065 -0.3048)
			(end 0.67945 -0.3048)
			(stroke
				(width 0.1)
				(type default)
			)
			(layer "F.Fab")
		)
		(fp_line
			(start 0.67945 -0.3048)
			(end 0.67945 0.3048)
			(stroke
				(width 0.1)
				(type default)
			)
			(layer "F.Fab")
		)
		(fp_line
			(start -0.67945 -0.305054)
			(end -0.12065 -0.305054)
			(stroke
				(width 0.1)
				(type default)
			)
			(layer "F.Fab")
		)
		(fp_line
			(start -0.12065 -0.305054)
			(end -0.12065 -0.2794)
			(stroke
				(width 0.1)
				(type default)
			)
			(layer "F.Fab")
		)
		(pad "1" smd circle
			(at -0.40005 0 270)
			(size 0 0)
			(layers "F.Cu" "F.Mask" "F.Paste")
			(net "P3V3_SSD10_CO_MODE")
		)
		(pad "2" smd circle
			(at 0.40005 0 270)
			(size 0 0)
			(layers "F.Cu" "F.Mask" "F.Paste")
			(net "GND")
		)
	)
	(footprint ""
		(layer "F.Cu")
		(at 244.492018 -236.682026 -90)
		(property "Reference" "R6243"
			(at 0 0 270)
			(layer "F.SilkS")
			(hide yes)
			(effects
				(font
					(size 1.27 1.27)
				)
			)
		)
		(property "Value" ""
			(at 0 0 270)
			(layer "F.Fab")
			(effects
				(font
					(size 1.27 1.27)
				)
			)
		)
		(duplicate_pad_numbers_are_jumpers no)
		(fp_line
			(start -0.7874 0.4064)
			(end -0.7874 -0.4064)
			(stroke
				(width 0.1524)
				(type default)
			)
			(layer "F.SilkS")
		)
		(fp_line
			(start 0.7874 0.4064)
			(end -0.7874 0.4064)
			(stroke
				(width 0.1524)
				(type default)
			)
			(layer "F.SilkS")
		)
		(fp_line
			(start -0.7874 -0.4064)
			(end 0.7874 -0.4064)
			(stroke
				(width 0.1524)
				(type default)
			)
			(layer "F.SilkS")
		)
		(fp_line
			(start 0.7874 -0.4064)
			(end 0.7874 0.4064)
			(stroke
				(width 0.1524)
				(type default)
			)
			(layer "F.SilkS")
		)
		(fp_line
			(start -0.67945 0.3048)
			(end -0.67945 -0.305054)
			(stroke
				(width 0.1)
				(type default)
			)
			(layer "F.Fab")
		)
		(fp_line
			(start -0.12065 0.3048)
			(end -0.67945 0.3048)
			(stroke
				(width 0.1)
				(type default)
			)
			(layer "F.Fab")
		)
		(fp_line
			(start 0.120396 0.3048)
			(end 0.120396 0.2794)
			(stroke
				(width 0.1)
				(type default)
			)
			(layer "F.Fab")
		)
		(fp_line
			(start 0.67945 0.3048)
			(end 0.120396 0.3048)
			(stroke
				(width 0.1)
				(type default)
			)
			(layer "F.Fab")
		)
		(fp_line
			(start -0.12065 0.2794)
			(end -0.12065 0.3048)
			(stroke
				(width 0.1)
				(type default)
			)
			(layer "F.Fab")
		)
		(fp_line
			(start 0.120396 0.2794)
			(end -0.12065 0.2794)
			(stroke
				(width 0.1)
				(type default)
			)
			(layer "F.Fab")
		)
		(fp_line
			(start -0.12065 -0.2794)
			(end 0.12065 -0.2794)
			(stroke
				(width 0.1)
				(type default)
			)
			(layer "F.Fab")
		)
		(fp_line
			(start 0.12065 -0.2794)
			(end 0.12065 -0.3048)
			(stroke
				(width 0.1)
				(type default)
			)
			(layer "F.Fab")
		)
		(fp_line
			(start 0.12065 -0.3048)
			(end 0.67945 -0.3048)
			(stroke
				(width 0.1)
				(type default)
			)
			(layer "F.Fab")
		)
		(fp_line
			(start 0.67945 -0.3048)
			(end 0.67945 0.3048)
			(stroke
				(width 0.1)
				(type default)
			)
			(layer "F.Fab")
		)
		(fp_line
			(start -0.67945 -0.305054)
			(end -0.12065 -0.305054)
			(stroke
				(width 0.1)
				(type default)
			)
			(layer "F.Fab")
		)
		(fp_line
			(start -0.12065 -0.305054)
			(end -0.12065 -0.2794)
			(stroke
				(width 0.1)
				(type default)
			)
			(layer "F.Fab")
		)
		(pad "1" smd circle
			(at -0.40005 0 270)
			(size 0 0)
			(layers "F.Cu" "F.Mask" "F.Paste")
			(net "SMB_BIC_RECOVER_IOEXP_SDA")
		)
		(pad "2" smd circle
			(at 0.40005 0 270)
			(size 0 0)
			(layers "F.Cu" "F.Mask" "F.Paste")
			(net "SMB_MB_R_SDA")
		)
	)
)
